FILE_TYPE = MACRO_DRAWING;
SET COLOR_WIRE YELLOW;
SET COLOR_PROP MONO;
SET COLOR_DOT WHITE;
SET COLOR_ARC YELLOW;
SET COLOR_BODY GREEN;
SET COLOR_NOTE MONO;
SET PROP_DISPLAY VALUE;
SET PAGE_NUMBER P163;
FORCEADD CAP_A..1
(-1800 3850);
FORCEPROP 1 LAST LOCATION C9M8
J 0
(-1750 3950);
DISPLAY 0.617021 (-1750 3950);
PAINT AQUA (-1750 3950);
FORCEPROP 1 LAST PART_NUMBER A36096-030
J 0
(-1750 3700);
DISPLAY 0.617021 (-1750 3700);
PAINT BLUE (-1750 3700);
FORCEPROP 1 LAST VALUE 0.1UF
J 0
(-1750 3900);
DISPLAY 0.617021 (-1750 3900);
PAINT SKYBLUE (-1750 3900);
FORCEPROP 1 LAST TOLERANCE 10%
J 0
(-1750 3800);
DISPLAY 0.617021 (-1750 3800);
PAINT SKYBLUE (-1750 3800);
FORCEPROP 1 LAST PACK_TYPE 0402V
J 0
(-1750 3650);
DISPLAY 0.617021 (-1750 3650);
PAINT SKYBLUE (-1750 3650);
FORCEPROP 1 LAST VOLTAGE 16V
J 0
(-1750 3850);
DISPLAY 0.617021 (-1750 3850);
PAINT SKYBLUE (-1750 3850);
FORCEPROP 1 LAST MATERIAL X7R
J 0
(-1750 3750);
DISPLAY 0.617021 (-1750 3750);
PAINT SKYBLUE (-1750 3750);
FORCEPROP 1 LASTPIN (-1800 3750) $PN 2
J 0
(-1790 3730);
DISPLAY 0.617021 (-1790 3730);
PAINT ORANGE (-1790 3730);
FORCEPROP 1 LASTPIN (-1800 3950) $PN 1
J 0
(-1790 3930);
DISPLAY 0.617021 (-1790 3930);
PAINT ORANGE (-1790 3930);
FORCEPROP 2 LAST CDS_LOCATION C9M8
J 0
(-1750 3950);
DISPLAY 0.617021 (-1750 3950);
PAINT AQUA (-1750 3950);
DISPLAY INVISIBLE (-1750 3950);
FORCEPROP 2 LAST CDS_LIB dev_discrete
J 0
(-1800 3850);
PAINT ORANGE (-1800 3850);
DISPLAY INVISIBLE (-1800 3850);
FORCEPROP 2 LAST SEC 1
J 0
(-1750 4050);
DISPLAY 0.680851 (-1750 4050);
PAINT MONO (-1750 4050);
DISPLAY INVISIBLE (-1750 4050);
FORCEPROP 2 LAST SEC_TYPE 0402V
J 0
(-1750 4050);
DISPLAY 1.021277 (-1750 4050);
PAINT ORANGE (-1750 4050);
DISPLAY INVISIBLE (-1750 4050);
FORCEPROP 1 LAST PATH I10
J 0
(-1750 4000);
DISPLAY 0.978723 (-1750 4000);
PAINT WHITE (-1750 4000);
DISPLAY INVISIBLE (-1750 4000);
FORCEPROP 0 LAST ROOM SMB_PE_HP_CPU1
J 0
(-1750 4050);
DISPLAY 1.021277 (-1750 4050);
PAINT ORANGE (-1750 4050);
DISPLAY INVISIBLE (-1750 4050);
FORCEADD GND..1
(-1800 3600);
FORCEPROP 3 LASTPIN (-1800 3650) SIG_NAME GND\g
J 0
(-1790 3660);
DISPLAY 0.659574 (-1790 3660);
PAINT MONO (-1790 3660);
DISPLAY INVISIBLE (-1790 3660);
FORCEPROP 2 LAST ROOM P2V5_LAN_AUX_VR
J 0
(-2100 3675);
DISPLAY 0.617021 (-2100 3675);
PAINT ORANGE (-2100 3675);
DISPLAY INVISIBLE (-2100 3675);
FORCEPROP 1 LAST PATH I11
J 0
(-1725 3600);
DISPLAY 0.872340 (-1725 3600);
PAINT AQUA (-1725 3600);
DISPLAY INVISIBLE (-1725 3600);
FORCEPROP 2 LAST BOM_COST NT_BASE_VRD
J 0
(-2100 3675);
DISPLAY 0.617021 (-2100 3675);
PAINT ORANGE (-2100 3675);
DISPLAY INVISIBLE (-2100 3675);
FORCEPROP 1 LAST SIZE 1B
J 0
(-1725 3550);
DISPLAY 0.872340 (-1725 3550);
PAINT GREEN (-1725 3550);
DISPLAY INVISIBLE (-1725 3550);
FORCEPROP 2 LAST CDS_LIB mstr_symbols
J 0
(-1800 3600);
PAINT MONO (-1800 3600);
DISPLAY INVISIBLE (-1800 3600);
FORCEPROP 1 LAST VOLTAGE 0
J 0
(-1800 3600);
PAINT SKYBLUE (-1800 3600);
DISPLAY INVISIBLE (-1800 3600);
FORCEPROP 1 LAST BODY_TYPE PLUMBING
J 0
(-1845 3557);
DISPLAY 0.340426 (-1845 3557);
PAINT GREEN (-1845 3557);
DISPLAY INVISIBLE (-1845 3557);
FORCEPROP 1 LAST HDL_POWER GND
J 0
(-1800 3750);
DISPLAY 0.872340 (-1800 3750);
PAINT GREEN (-1800 3750);
DISPLAY INVISIBLE (-1800 3750);
FORCEADD CAP_A..1
R 2
(-1150 3850);
FORCEPROP 1 LAST PACK_TYPE 0402V
J 2
(-1200 3650);
DISPLAY 0.617021 (-1200 3650);
PAINT SKYBLUE (-1200 3650);
FORCEPROP 1 LAST PART_NUMBER A36096-030
J 2
(-1200 3700);
DISPLAY 0.617021 (-1200 3700);
PAINT BLUE (-1200 3700);
FORCEPROP 1 LAST LOCATION C9M7
J 2
(-1200 3950);
DISPLAY 0.617021 (-1200 3950);
PAINT AQUA (-1200 3950);
FORCEPROP 1 LAST VALUE 0.1UF
J 2
(-1200 3900);
DISPLAY 0.617021 (-1200 3900);
PAINT SKYBLUE (-1200 3900);
FORCEPROP 1 LAST TOLERANCE 10%
J 2
(-1200 3800);
DISPLAY 0.617021 (-1200 3800);
PAINT SKYBLUE (-1200 3800);
FORCEPROP 1 LAST VOLTAGE 16V
J 2
(-1200 3850);
DISPLAY 0.617021 (-1200 3850);
PAINT SKYBLUE (-1200 3850);
FORCEPROP 1 LAST MATERIAL X7R
J 2
(-1200 3750);
DISPLAY 0.617021 (-1200 3750);
PAINT SKYBLUE (-1200 3750);
FORCEPROP 1 LASTPIN (-1150 3950) $PN 1
J 2
(-1160 3930);
DISPLAY 0.617021 (-1160 3930);
PAINT ORANGE (-1160 3930);
FORCEPROP 1 LASTPIN (-1150 3750) $PN 2
J 2
(-1160 3730);
DISPLAY 0.617021 (-1160 3730);
PAINT ORANGE (-1160 3730);
FORCEPROP 2 LAST SEC_TYPE 0402V
J 0
(-1200 4050);
DISPLAY 1.021277 (-1200 4050);
PAINT ORANGE (-1200 4050);
DISPLAY INVISIBLE (-1200 4050);
FORCEPROP 2 LAST SEC 1
J 0
(-1200 4050);
DISPLAY 0.680851 (-1200 4050);
PAINT MONO (-1200 4050);
DISPLAY INVISIBLE (-1200 4050);
FORCEPROP 2 LAST CDS_LIB dev_discrete
J 0
(-1150 3850);
PAINT ORANGE (-1150 3850);
DISPLAY INVISIBLE (-1150 3850);
FORCEPROP 2 LAST CDS_LOCATION C9M7
J 2
(-1200 3950);
DISPLAY 0.617021 (-1200 3950);
PAINT AQUA (-1200 3950);
DISPLAY INVISIBLE (-1200 3950);
FORCEPROP 1 LAST PATH I12
J 2
(-1200 4000);
DISPLAY 0.978723 (-1200 4000);
PAINT WHITE (-1200 4000);
DISPLAY INVISIBLE (-1200 4000);
FORCEPROP 0 LAST ROOM SMB_PE_HP_CPU1
J 0
(-1200 4050);
DISPLAY 1.021277 (-1200 4050);
PAINT ORANGE (-1200 4050);
DISPLAY INVISIBLE (-1200 4050);
FORCEADD GND..1
(-1150 3600);
FORCEPROP 3 LASTPIN (-1150 3650) SIG_NAME GND\g
J 0
(-1140 3660);
DISPLAY 0.659574 (-1140 3660);
PAINT MONO (-1140 3660);
DISPLAY INVISIBLE (-1140 3660);
FORCEPROP 2 LAST ROOM P2V5_LAN_AUX_VR
J 0
(-1450 3675);
DISPLAY 0.617021 (-1450 3675);
PAINT ORANGE (-1450 3675);
DISPLAY INVISIBLE (-1450 3675);
FORCEPROP 1 LAST PATH I13
J 0
(-1075 3600);
DISPLAY 0.872340 (-1075 3600);
PAINT AQUA (-1075 3600);
DISPLAY INVISIBLE (-1075 3600);
FORCEPROP 2 LAST BOM_COST NT_BASE_VRD
J 0
(-1450 3675);
DISPLAY 0.617021 (-1450 3675);
PAINT ORANGE (-1450 3675);
DISPLAY INVISIBLE (-1450 3675);
FORCEPROP 1 LAST SIZE 1B
J 0
(-1075 3550);
DISPLAY 0.872340 (-1075 3550);
PAINT GREEN (-1075 3550);
DISPLAY INVISIBLE (-1075 3550);
FORCEPROP 2 LAST CDS_LIB mstr_symbols
J 0
(-1150 3600);
PAINT MONO (-1150 3600);
DISPLAY INVISIBLE (-1150 3600);
FORCEPROP 1 LAST VOLTAGE 0
J 0
(-1150 3600);
PAINT SKYBLUE (-1150 3600);
DISPLAY INVISIBLE (-1150 3600);
FORCEPROP 1 LAST BODY_TYPE PLUMBING
J 0
(-1195 3557);
DISPLAY 0.340426 (-1195 3557);
PAINT GREEN (-1195 3557);
DISPLAY INVISIBLE (-1195 3557);
FORCEPROP 1 LAST HDL_POWER GND
J 0
(-1150 3750);
DISPLAY 0.872340 (-1150 3750);
PAINT GREEN (-1150 3750);
DISPLAY INVISIBLE (-1150 3750);
FORCEADD RES..2
R 2
(-600 3650);
FORCEPROP 1 LASTPIN (-600 3750) $PN 1
J 2
(-605 3712);
DISPLAY 0.617021 (-605 3712);
PAINT ORANGE (-605 3712);
FORCEPROP 1 LAST PACK_TYPE 0402
J 2
(-640 3475);
DISPLAY 0.617021 (-640 3475);
PAINT SKYBLUE (-640 3475);
FORCEPROP 1 LASTPIN (-600 3550) $PN 2
J 2
(-605 3560);
DISPLAY 0.617021 (-605 3560);
PAINT ORANGE (-605 3560);
FORCEPROP 1 LAST MATERIAL CHIP
J 2
(-640 3575);
DISPLAY 0.617021 (-640 3575);
PAINT SKYBLUE (-640 3575);
FORCEPROP 1 LAST TOLERANCE 1%
J 2
(-645 3675);
DISPLAY 0.617021 (-645 3675);
PAINT SKYBLUE (-645 3675);
FORCEPROP 1 LAST WATTAGE 1/16W
J 2
(-640 3625);
DISPLAY 0.617021 (-640 3625);
PAINT SKYBLUE (-640 3625);
FORCEPROP 1 LAST VALUE 2.0K
J 2
(-645 3725);
DISPLAY 0.617021 (-645 3725);
PAINT SKYBLUE (-645 3725);
FORCEPROP 1 LAST LOCATION R9M17
J 2
(-645 3775);
DISPLAY 0.617021 (-645 3775);
PAINT AQUA (-645 3775);
FORCEPROP 1 LAST PART_NUMBER G21796-001
J 2
(-640 3525);
DISPLAY 0.617021 (-640 3525);
PAINT BLUE (-640 3525);
FORCEPROP 0 LAST ROOM SMB_PE_HP_CPU1
J 0
(-625 3875);
DISPLAY 1.021277 (-625 3875);
PAINT ORANGE (-625 3875);
DISPLAY INVISIBLE (-625 3875);
FORCEPROP 1 LAST PATH I15
J 2
(-650 3825);
DISPLAY 0.978723 (-650 3825);
PAINT WHITE (-650 3825);
DISPLAY INVISIBLE (-650 3825);
FORCEPROP 2 LAST CDS_LIB mstr_discrete
J 2
(-600 3650);
PAINT MONO (-600 3650);
DISPLAY INVISIBLE (-600 3650);
FORCEPROP 2 LAST SEC_TYPE 0402
J 0
(-650 3875);
DISPLAY 1.021277 (-650 3875);
PAINT ORANGE (-650 3875);
DISPLAY INVISIBLE (-650 3875);
FORCEPROP 2 LAST SEC 1
J 0
(-650 3875);
DISPLAY 0.680851 (-650 3875);
PAINT MONO (-650 3875);
DISPLAY INVISIBLE (-650 3875);
FORCEPROP 2 LAST CDS_LOCATION R9M17
J 2
(-645 3775);
DISPLAY 0.617021 (-645 3775);
PAINT AQUA (-645 3775);
DISPLAY INVISIBLE (-645 3775);
FORCEADD RES..2
(-450 3650);
FORCEPROP 1 LASTPIN (-450 3550) $PN 2
J 0
(-445 3560);
DISPLAY 0.617021 (-445 3560);
PAINT ORANGE (-445 3560);
FORCEPROP 1 LASTPIN (-450 3750) $PN 1
J 0
(-445 3712);
DISPLAY 0.617021 (-445 3712);
PAINT ORANGE (-445 3712);
FORCEPROP 1 LAST WATTAGE 1/16W
J 0
(-410 3625);
DISPLAY 0.617021 (-410 3625);
PAINT SKYBLUE (-410 3625);
FORCEPROP 1 LAST PACK_TYPE 0402
J 0
(-410 3475);
DISPLAY 0.617021 (-410 3475);
PAINT SKYBLUE (-410 3475);
FORCEPROP 1 LAST TOLERANCE 1%
J 0
(-405 3675);
DISPLAY 0.617021 (-405 3675);
PAINT SKYBLUE (-405 3675);
FORCEPROP 1 LAST PART_NUMBER G21796-001
J 0
(-410 3525);
DISPLAY 0.617021 (-410 3525);
PAINT BLUE (-410 3525);
FORCEPROP 1 LAST MATERIAL CHIP
J 0
(-410 3575);
DISPLAY 0.617021 (-410 3575);
PAINT SKYBLUE (-410 3575);
FORCEPROP 1 LAST LOCATION R9M16
J 0
(-405 3775);
DISPLAY 0.617021 (-405 3775);
PAINT AQUA (-405 3775);
FORCEPROP 1 LAST VALUE 2.0K
J 0
(-405 3725);
DISPLAY 0.617021 (-405 3725);
PAINT SKYBLUE (-405 3725);
FORCEPROP 0 LAST ROOM SMB_PE_HP_CPU1
J 0
(-400 3875);
DISPLAY 1.021277 (-400 3875);
PAINT ORANGE (-400 3875);
DISPLAY INVISIBLE (-400 3875);
FORCEPROP 1 LAST PATH I16
J 0
(-400 3825);
DISPLAY 0.978723 (-400 3825);
PAINT WHITE (-400 3825);
DISPLAY INVISIBLE (-400 3825);
FORCEPROP 2 LAST SEC_TYPE 0402
J 0
(-400 3875);
DISPLAY 1.021277 (-400 3875);
PAINT ORANGE (-400 3875);
DISPLAY INVISIBLE (-400 3875);
FORCEPROP 2 LAST CDS_LIB mstr_discrete
J 0
(-450 3650);
PAINT MONO (-450 3650);
DISPLAY INVISIBLE (-450 3650);
FORCEPROP 2 LAST SEC 1
J 0
(-400 3875);
DISPLAY 0.680851 (-400 3875);
PAINT MONO (-400 3875);
DISPLAY INVISIBLE (-400 3875);
FORCEPROP 2 LAST CDS_LOCATION R9M16
J 0
(-405 3775);
DISPLAY 0.617021 (-405 3775);
PAINT AQUA (-405 3775);
DISPLAY INVISIBLE (-405 3775);
FORCEADD OFFPAGE..3
(1100 3250);
FORCEPROP 2 LAST $XR1 182 
J 0
(1434 3250);
DISPLAY 0.638298 (1434 3250);
PAINT MONO (1434 3250);
FORCEPROP 2 LAST $XR0 145 
J 0
(1314 3250);
DISPLAY 0.638298 (1314 3250);
PAINT MONO (1314 3250);
FORCEPROP 2 LAST PATH I18
J 2
(1050 3325);
DISPLAY 1.021277 (1050 3325);
PAINT ORANGE (1050 3325);
DISPLAY INVISIBLE (1050 3325);
FORCEPROP 2 LAST CDS_LIB mstr_standard
J 2
(1100 3250);
PAINT MONO (1100 3250);
DISPLAY INVISIBLE (1100 3250);
FORCEPROP 1 LAST OFFPAGE TRUE
J 0
(1425 3125);
DISPLAY 0.872340 (1425 3125);
PAINT GREEN (1425 3125);
DISPLAY INVISIBLE (1425 3125);
FORCEPROP 1 LAST COMMENT_BODY TRUE
J 0
(1050 3150);
DISPLAY 0.872340 (1050 3150);
PAINT GREEN (1050 3150);
DISPLAY INVISIBLE (1050 3150);
FORCEADD OFFPAGE..2
(1100 3300);
FORCEPROP 2 LAST $XR1 182 
J 0
(1409 3300);
DISPLAY 0.638298 (1409 3300);
PAINT MONO (1409 3300);
FORCEPROP 2 LAST $XR0 145 
J 0
(1289 3300);
DISPLAY 0.638298 (1289 3300);
PAINT MONO (1289 3300);
FORCEPROP 2 LAST PATH I19
J 2
(1050 3375);
DISPLAY 1.021277 (1050 3375);
PAINT ORANGE (1050 3375);
DISPLAY INVISIBLE (1050 3375);
FORCEPROP 2 LAST CDS_LIB mstr_standard
J 2
(1100 3300);
PAINT MONO (1100 3300);
DISPLAY INVISIBLE (1100 3300);
FORCEPROP 1 LAST OFFPAGE TRUE
J 0
(1425 3175);
DISPLAY 0.872340 (1425 3175);
PAINT GREEN (1425 3175);
DISPLAY INVISIBLE (1425 3175);
FORCEPROP 1 LAST COMMENT_BODY TRUE
J 0
(1055 3205);
DISPLAY 0.872340 (1055 3205);
PAINT GREEN (1055 3205);
DISPLAY INVISIBLE (1055 3205);
FORCEADD RES..1
(-3800 3300);
FORCEPROP 1 LASTPIN (-3700 3300) $PN 2
J 0
(-3738 3312);
DISPLAY 0.617021 (-3738 3312);
PAINT ORANGE (-3738 3312);
FORCEPROP 1 LASTPIN (-3900 3300) $PN 1
J 0
(-3888 3312);
DISPLAY 0.617021 (-3888 3312);
PAINT ORANGE (-3888 3312);
FORCEPROP 1 LAST WATTAGE 1/16W
J 2
(-3925 3250);
DISPLAY 0.617021 (-3925 3250);
PAINT SKYBLUE (-3925 3250);
FORCEPROP 1 LAST MATERIAL CHIP
J 0
(-3850 3250);
DISPLAY 0.617021 (-3850 3250);
PAINT SKYBLUE (-3850 3250);
FORCEPROP 1 LAST PACK_TYPE 0402
J 0
(-3650 3250);
DISPLAY 0.617021 (-3650 3250);
PAINT SKYBLUE (-3650 3250);
FORCEPROP 1 LAST TOLERANCE 1%
J 0
(-3650 3325);
DISPLAY 0.617021 (-3650 3325);
PAINT SKYBLUE (-3650 3325);
FORCEPROP 1 LAST VALUE 10.0
J 2
(-3475 3325);
DISPLAY 0.617021 (-3475 3325);
PAINT SKYBLUE (-3475 3325);
FORCEPROP 1 LAST PART_NUMBER G21796-066
J 0
(-3900 3200);
DISPLAY 0.617021 (-3900 3200);
PAINT BLUE (-3900 3200);
FORCEPROP 1 LAST LOCATION R6N8
J 0
(-3800 3375);
DISPLAY 0.617021 (-3800 3375);
PAINT AQUA (-3800 3375);
FORCEPROP 0 LAST ROOM CPU1
J 0
(-3800 3475);
DISPLAY 1.021277 (-3800 3475);
PAINT ORANGE (-3800 3475);
DISPLAY INVISIBLE (-3800 3475);
FORCEPROP 1 LAST PATH I2
J 0
(-3850 3450);
DISPLAY 0.978723 (-3850 3450);
PAINT WHITE (-3850 3450);
DISPLAY INVISIBLE (-3850 3450);
FORCEPROP 2 LAST SEC_TYPE 0402
J 0
(-3850 3500);
DISPLAY 1.021277 (-3850 3500);
PAINT ORANGE (-3850 3500);
DISPLAY INVISIBLE (-3850 3500);
FORCEPROP 2 LAST CDS_LIB mstr_discrete
J 0
(-3800 3300);
PAINT MONO (-3800 3300);
DISPLAY INVISIBLE (-3800 3300);
FORCEPROP 2 LAST SEC 1
J 0
(-3850 3500);
DISPLAY 0.680851 (-3850 3500);
PAINT MONO (-3850 3500);
DISPLAY INVISIBLE (-3850 3500);
FORCEPROP 2 LAST CDS_LOCATION R6N8
J 0
(-3800 3375);
DISPLAY 0.617021 (-3800 3375);
PAINT AQUA (-3800 3375);
DISPLAY INVISIBLE (-3800 3375);
FORCEADD RES..1
(-50 3300);
FORCEPROP 1 LASTPIN (-150 3300) $PN 1
J 0
(-138 3312);
DISPLAY 0.787234 (-138 3312);
PAINT ORANGE (-138 3312);
FORCEPROP 1 LASTPIN (50 3300) $PN 2
J 0
(12 3312);
DISPLAY 0.787234 (12 3312);
PAINT ORANGE (12 3312);
FORCEPROP 1 LAST TOLERANCE 1%
J 0
(-50 3200);
DISPLAY 0.617021 (-50 3200);
PAINT SKYBLUE (-50 3200);
FORCEPROP 1 LAST LOCATION R9M14
J 0
(-100 3350);
DISPLAY 0.617021 (-100 3350);
PAINT AQUA (-100 3350);
FORCEPROP 1 LAST PART_NUMBER G21796-173
J 0
(-100 3400);
DISPLAY 0.617021 (-100 3400);
PAINT BLUE (-100 3400);
FORCEPROP 1 LAST PACK_TYPE 0402
J 0
(-75 3100);
DISPLAY 0.617021 (-75 3100);
PAINT SKYBLUE (-75 3100);
FORCEPROP 1 LAST VALUE 20.0
J 2
(-75 3200);
DISPLAY 0.617021 (-75 3200);
PAINT SKYBLUE (-75 3200);
FORCEPROP 1 LAST WATTAGE 1/16W
J 2
(-75 3150);
DISPLAY 0.617021 (-75 3150);
PAINT SKYBLUE (-75 3150);
FORCEPROP 1 LAST MATERIAL CHIP
J 0
(-50 3150);
DISPLAY 0.617021 (-50 3150);
PAINT SKYBLUE (-50 3150);
FORCEPROP 2 LAST SEC_TYPE 0402
J 0
(-100 3500);
DISPLAY 1.021277 (-100 3500);
PAINT ORANGE (-100 3500);
DISPLAY INVISIBLE (-100 3500);
FORCEPROP 2 LAST SEC 1
J 0
(-100 3500);
PAINT MONO (-100 3500);
DISPLAY INVISIBLE (-100 3500);
FORCEPROP 0 LAST ROOM SMB_PE_HP_CPU1
J 0
(-100 3500);
DISPLAY 1.021277 (-100 3500);
PAINT ORANGE (-100 3500);
DISPLAY INVISIBLE (-100 3500);
FORCEPROP 1 LAST PATH I20
J 0
(-100 3450);
DISPLAY 0.978723 (-100 3450);
PAINT WHITE (-100 3450);
DISPLAY INVISIBLE (-100 3450);
FORCEPROP 2 LAST CDS_LIB mstr_discrete
J 0
(-50 3300);
PAINT ORANGE (-50 3300);
DISPLAY INVISIBLE (-50 3300);
FORCEPROP 2 LAST CDS_LOCATION R9M14
J 0
(-100 3350);
DISPLAY 0.617021 (-100 3350);
PAINT AQUA (-100 3350);
DISPLAY INVISIBLE (-100 3350);
FORCEADD RES..1
(200 3250);
FORCEPROP 1 LASTPIN (100 3250) $PN 1
J 0
(112 3262);
DISPLAY 0.787234 (112 3262);
PAINT ORANGE (112 3262);
FORCEPROP 1 LASTPIN (300 3250) $PN 2
J 0
(262 3262);
DISPLAY 0.787234 (262 3262);
PAINT ORANGE (262 3262);
FORCEPROP 1 LAST WATTAGE 1/16W
J 2
(175 3100);
DISPLAY 0.617021 (175 3100);
PAINT SKYBLUE (175 3100);
FORCEPROP 1 LAST LOCATION R9M13
J 0
(150 3300);
DISPLAY 0.617021 (150 3300);
PAINT AQUA (150 3300);
FORCEPROP 1 LAST PART_NUMBER G21796-173
J 0
(150 3350);
DISPLAY 0.617021 (150 3350);
PAINT BLUE (150 3350);
FORCEPROP 1 LAST MATERIAL CHIP
J 0
(200 3100);
DISPLAY 0.617021 (200 3100);
PAINT SKYBLUE (200 3100);
FORCEPROP 1 LAST VALUE 20.0
J 2
(175 3150);
DISPLAY 0.617021 (175 3150);
PAINT SKYBLUE (175 3150);
FORCEPROP 1 LAST TOLERANCE 1%
J 0
(200 3150);
DISPLAY 0.617021 (200 3150);
PAINT SKYBLUE (200 3150);
FORCEPROP 1 LAST PACK_TYPE 0402
J 0
(200 3050);
DISPLAY 0.617021 (200 3050);
PAINT SKYBLUE (200 3050);
FORCEPROP 2 LAST SEC_TYPE 0402
J 0
(150 3450);
DISPLAY 1.021277 (150 3450);
PAINT ORANGE (150 3450);
DISPLAY INVISIBLE (150 3450);
FORCEPROP 2 LAST SEC 1
J 0
(150 3450);
PAINT MONO (150 3450);
DISPLAY INVISIBLE (150 3450);
FORCEPROP 0 LAST ROOM SMB_PE_HP_CPU1
J 0
(150 3450);
DISPLAY 1.021277 (150 3450);
PAINT ORANGE (150 3450);
DISPLAY INVISIBLE (150 3450);
FORCEPROP 1 LAST PATH I21
J 0
(150 3400);
DISPLAY 0.978723 (150 3400);
PAINT WHITE (150 3400);
DISPLAY INVISIBLE (150 3400);
FORCEPROP 2 LAST CDS_LIB mstr_discrete
J 0
(200 3250);
PAINT ORANGE (200 3250);
DISPLAY INVISIBLE (200 3250);
FORCEPROP 2 LAST CDS_LOCATION R9M13
J 0
(150 3300);
DISPLAY 0.617021 (150 3300);
PAINT AQUA (150 3300);
DISPLAY INVISIBLE (150 3300);
FORCEADD P3V3_STBY..1
(-1100 4150);
FORCEPROP 3 LASTPIN (-1100 4100) SIG_NAME P3V3_STBY\g
J 0
(-1090 4110);
DISPLAY 0.659574 (-1090 4110);
PAINT MONO (-1090 4110);
DISPLAY INVISIBLE (-1090 4110);
FORCEPROP 1 LAST VOLTAGE 3.3V
J 0
(-1145 4107);
DISPLAY 0.340426 (-1145 4107);
PAINT SKYBLUE (-1145 4107);
DISPLAY INVISIBLE (-1145 4107);
FORCEPROP 2 LAST CDS_LIB mstr_symbols
J 0
(-1100 4150);
PAINT ORANGE (-1100 4150);
DISPLAY INVISIBLE (-1100 4150);
FORCEPROP 1 LAST SIZE 1B
J 0
(-1055 4172);
DISPLAY 0.340426 (-1055 4172);
PAINT GREEN (-1055 4172);
DISPLAY INVISIBLE (-1055 4172);
FORCEPROP 1 LAST PATH I26
J 0
(-1055 4152);
DISPLAY 0.340426 (-1055 4152);
PAINT GREEN (-1055 4152);
DISPLAY INVISIBLE (-1055 4152);
FORCEPROP 1 LAST BODY_TYPE PLUMBING
J 0
(-1145 4107);
DISPLAY 0.340426 (-1145 4107);
PAINT GREEN (-1145 4107);
DISPLAY INVISIBLE (-1145 4107);
FORCEPROP 1 LAST HDL_POWER P3V3_STBY
J 0
(-1400 4025);
DISPLAY 0.872340 (-1400 4025);
PAINT ORANGE (-1400 4025);
DISPLAY INVISIBLE (-1400 4025);
FORCEADD P3V3_STBY..1
(-525 4050);
FORCEPROP 3 LASTPIN (-525 4000) SIG_NAME P3V3_STBY\g
J 0
(-515 4010);
DISPLAY 0.659574 (-515 4010);
PAINT MONO (-515 4010);
DISPLAY INVISIBLE (-515 4010);
FORCEPROP 1 LAST PATH I27
J 0
(-480 4052);
DISPLAY 0.340426 (-480 4052);
PAINT GREEN (-480 4052);
DISPLAY INVISIBLE (-480 4052);
FORCEPROP 2 LAST CDS_LIB mstr_symbols
J 0
(-525 4050);
PAINT ORANGE (-525 4050);
DISPLAY INVISIBLE (-525 4050);
FORCEPROP 1 LAST SIZE 1B
J 0
(-480 4072);
DISPLAY 0.340426 (-480 4072);
PAINT GREEN (-480 4072);
DISPLAY INVISIBLE (-480 4072);
FORCEPROP 1 LAST VOLTAGE 3.3V
J 0
(-570 4007);
DISPLAY 0.340426 (-570 4007);
PAINT SKYBLUE (-570 4007);
DISPLAY INVISIBLE (-570 4007);
FORCEPROP 1 LAST BODY_TYPE PLUMBING
J 0
(-570 4007);
DISPLAY 0.340426 (-570 4007);
PAINT GREEN (-570 4007);
DISPLAY INVISIBLE (-570 4007);
FORCEPROP 1 LAST HDL_POWER P3V3_STBY
J 0
(-825 3925);
DISPLAY 0.872340 (-825 3925);
PAINT ORANGE (-825 3925);
DISPLAY INVISIBLE (-825 3925);
FORCEADD TCA9517DGKR-GP..1
(-1475 3275);
FORCEPROP 1 LAST LOCATION U1B2
J 0
(-1645 3460);
DISPLAY 0.617021 (-1645 3460);
PAINT GREEN (-1645 3460);
FORCEPROP 2 LASTPIN (-1150 3250) $PN 6
J 0
(-1140 3260);
DISPLAY 0.808511 (-1140 3260);
PAINT ORANGE (-1140 3260);
FORCEPROP 2 LASTPIN (-1150 3300) $PN 7
J 0
(-1140 3310);
DISPLAY 0.808511 (-1140 3310);
PAINT ORANGE (-1140 3310);
FORCEPROP 2 LASTPIN (-1150 3350) $PN 8
J 0
(-1140 3360);
DISPLAY 0.808511 (-1140 3360);
PAINT ORANGE (-1140 3360);
FORCEPROP 2 LASTPIN (-1800 3200) $PN 4
J 2
(-1810 3210);
DISPLAY 0.808511 (-1810 3210);
PAINT ORANGE (-1810 3210);
FORCEPROP 2 LASTPIN (-1800 3250) $PN 3
J 2
(-1810 3260);
DISPLAY 0.808511 (-1810 3260);
PAINT ORANGE (-1810 3260);
FORCEPROP 2 LASTPIN (-1800 3300) $PN 2
J 2
(-1810 3310);
DISPLAY 0.808511 (-1810 3310);
PAINT ORANGE (-1810 3310);
FORCEPROP 2 LASTPIN (-1800 3350) $PN 1
J 2
(-1810 3360);
DISPLAY 0.808511 (-1810 3360);
PAINT ORANGE (-1810 3360);
FORCEPROP 1 LAST VALUE TCA9517DGKR-GP
J 0
(-1645 3065);
DISPLAY 0.617021 (-1645 3065);
PAINT GREEN (-1645 3065);
FORCEPROP 2 LASTPIN (-1150 3200) $PN 5
J 0
(-1140 3210);
DISPLAY 0.808511 (-1140 3210);
PAINT ORANGE (-1140 3210);
FORCEPROP 1 LAST PACK_TYPE DISCRET-G8
J 0
(-1475 3275);
DISPLAY 0.617021 (-1475 3275);
PAINT GREEN (-1475 3275);
DISPLAY INVISIBLE (-1475 3275);
FORCEPROP 2 LAST SEC 1
J 0
(-1625 3500);
DISPLAY 0.680851 (-1625 3500);
PAINT MONO (-1625 3500);
DISPLAY INVISIBLE (-1625 3500);
FORCEPROP 2 LAST SEC_TYPE DISCRET-G8
J 0
(-1625 3500);
DISPLAY 1.021277 (-1625 3500);
PAINT ORANGE (-1625 3500);
DISPLAY INVISIBLE (-1625 3500);
FORCEPROP 1 LAST CDS_LMAN_SYM_OUTLINE -175,175,175,-175
J 0
(-1475 3275);
DISPLAY 0.468085 (-1475 3275);
PAINT GREEN (-1475 3275);
DISPLAY INVISIBLE (-1475 3275);
FORCEPROP 1 LAST PATH I28
J 0
(-1475 3275);
DISPLAY 0.617021 (-1475 3275);
PAINT GREEN (-1475 3275);
DISPLAY INVISIBLE (-1475 3275);
FORCEPROP 2 LAST CDS_LIB w_hdl
J 0
(-1475 3275);
PAINT MONO (-1475 3275);
DISPLAY INVISIBLE (-1475 3275);
FORCEPROP 1 LAST PART_NUMBER 071.09517.0009
J 0
(-1475 3275);
DISPLAY 0.617021 (-1475 3275);
PAINT GREEN (-1475 3275);
DISPLAY INVISIBLE (-1475 3275);
FORCEADD GND..1
(-1900 3100);
FORCEPROP 3 LASTPIN (-1900 3150) SIG_NAME GND\g
J 0
(-1890 3160);
DISPLAY 0.659574 (-1890 3160);
PAINT MONO (-1890 3160);
DISPLAY INVISIBLE (-1890 3160);
FORCEPROP 1 LAST PATH I29
J 0
(-1825 3100);
DISPLAY 0.872340 (-1825 3100);
PAINT AQUA (-1825 3100);
DISPLAY INVISIBLE (-1825 3100);
FORCEPROP 2 LAST ROOM P2V5_LAN_AUX_VR
J 0
(-2200 3175);
DISPLAY 0.617021 (-2200 3175);
PAINT ORANGE (-2200 3175);
DISPLAY INVISIBLE (-2200 3175);
FORCEPROP 2 LAST BOM_COST NT_BASE_VRD
J 0
(-2200 3175);
DISPLAY 0.617021 (-2200 3175);
PAINT ORANGE (-2200 3175);
DISPLAY INVISIBLE (-2200 3175);
FORCEPROP 1 LAST SIZE 1B
J 0
(-1825 3050);
DISPLAY 0.872340 (-1825 3050);
PAINT GREEN (-1825 3050);
DISPLAY INVISIBLE (-1825 3050);
FORCEPROP 2 LAST CDS_LIB mstr_symbols
J 0
(-1900 3100);
PAINT MONO (-1900 3100);
DISPLAY INVISIBLE (-1900 3100);
FORCEPROP 1 LAST VOLTAGE 0
J 0
(-1900 3100);
PAINT SKYBLUE (-1900 3100);
DISPLAY INVISIBLE (-1900 3100);
FORCEPROP 1 LAST BODY_TYPE PLUMBING
J 0
(-1945 3057);
DISPLAY 0.340426 (-1945 3057);
PAINT GREEN (-1945 3057);
DISPLAY INVISIBLE (-1945 3057);
FORCEPROP 1 LAST HDL_POWER GND
J 0
(-1900 3250);
DISPLAY 0.872340 (-1900 3250);
PAINT GREEN (-1900 3250);
DISPLAY INVISIBLE (-1900 3250);
FORCEADD RES..1
(-3275 3250);
FORCEPROP 1 LASTPIN (-3175 3250) $PN 2
J 0
(-3213 3262);
DISPLAY 0.617021 (-3213 3262);
PAINT ORANGE (-3213 3262);
FORCEPROP 1 LASTPIN (-3375 3250) $PN 1
J 0
(-3363 3262);
DISPLAY 0.617021 (-3363 3262);
PAINT ORANGE (-3363 3262);
FORCEPROP 1 LAST WATTAGE 1/16W
J 2
(-3400 3200);
DISPLAY 0.617021 (-3400 3200);
PAINT SKYBLUE (-3400 3200);
FORCEPROP 1 LAST MATERIAL CHIP
J 0
(-3325 3200);
DISPLAY 0.617021 (-3325 3200);
PAINT SKYBLUE (-3325 3200);
FORCEPROP 1 LAST PACK_TYPE 0402
J 0
(-3125 3200);
DISPLAY 0.617021 (-3125 3200);
PAINT SKYBLUE (-3125 3200);
FORCEPROP 1 LAST TOLERANCE 1%
J 0
(-3125 3275);
DISPLAY 0.617021 (-3125 3275);
PAINT SKYBLUE (-3125 3275);
FORCEPROP 1 LAST VALUE 10.0
J 2
(-2950 3275);
DISPLAY 0.617021 (-2950 3275);
PAINT SKYBLUE (-2950 3275);
FORCEPROP 1 LAST PART_NUMBER G21796-066
J 0
(-3425 3150);
DISPLAY 0.617021 (-3425 3150);
PAINT BLUE (-3425 3150);
FORCEPROP 1 LAST LOCATION R6N9
J 0
(-3275 3350);
DISPLAY 0.617021 (-3275 3350);
PAINT AQUA (-3275 3350);
FORCEPROP 0 LAST ROOM CPU1
J 0
(-3275 3450);
DISPLAY 1.021277 (-3275 3450);
PAINT ORANGE (-3275 3450);
DISPLAY INVISIBLE (-3275 3450);
FORCEPROP 1 LAST PATH I3
J 0
(-3325 3400);
DISPLAY 0.978723 (-3325 3400);
PAINT WHITE (-3325 3400);
DISPLAY INVISIBLE (-3325 3400);
FORCEPROP 2 LAST SEC_TYPE 0402
J 0
(-3325 3450);
DISPLAY 1.021277 (-3325 3450);
PAINT ORANGE (-3325 3450);
DISPLAY INVISIBLE (-3325 3450);
FORCEPROP 2 LAST CDS_LIB mstr_discrete
J 0
(-3275 3250);
PAINT MONO (-3275 3250);
DISPLAY INVISIBLE (-3275 3250);
FORCEPROP 2 LAST SEC 1
J 0
(-3325 3450);
DISPLAY 0.680851 (-3325 3450);
PAINT MONO (-3325 3450);
DISPLAY INVISIBLE (-3325 3450);
FORCEPROP 2 LAST CDS_LOCATION R6N9
J 0
(-3275 3350);
DISPLAY 0.617021 (-3275 3350);
PAINT AQUA (-3275 3350);
DISPLAY INVISIBLE (-3275 3350);
FORCEADD OFFPAGE..1
(-4675 3300);
FORCEPROP 2 LAST $XR0 55 
J 0
(-4896 3300);
DISPLAY 0.638298 (-4896 3300);
PAINT MONO (-4896 3300);
FORCEPROP 2 LAST PATH I4
J 0
(-4625 3375);
DISPLAY 1.021277 (-4625 3375);
PAINT ORANGE (-4625 3375);
DISPLAY INVISIBLE (-4625 3375);
FORCEPROP 2 LAST CDS_LIB mstr_standard
J 0
(-4675 3300);
PAINT MONO (-4675 3300);
DISPLAY INVISIBLE (-4675 3300);
FORCEPROP 1 LAST OFFPAGE TRUE
J 0
(-4350 3175);
DISPLAY 0.872340 (-4350 3175);
PAINT GREEN (-4350 3175);
DISPLAY INVISIBLE (-4350 3175);
FORCEPROP 1 LAST COMMENT_BODY TRUE
J 0
(-4550 3200);
DISPLAY 0.872340 (-4550 3200);
PAINT GREEN (-4550 3200);
DISPLAY INVISIBLE (-4550 3200);
FORCEADD OFFPAGE..3
R 2
(-4675 3250);
FORCEPROP 2 LAST $XR0 55 
J 0
(-4924 3250);
DISPLAY 0.638298 (-4924 3250);
PAINT MONO (-4924 3250);
FORCEPROP 2 LAST PATH I5
J 2
(-4725 3325);
DISPLAY 1.021277 (-4725 3325);
PAINT ORANGE (-4725 3325);
DISPLAY INVISIBLE (-4725 3325);
FORCEPROP 2 LAST CDS_LIB mstr_standard
J 2
(-4675 3250);
PAINT MONO (-4675 3250);
DISPLAY INVISIBLE (-4675 3250);
FORCEPROP 1 LAST OFFPAGE TRUE
J 2
(-5000 3125);
DISPLAY 0.872340 (-5000 3125);
PAINT GREEN (-5000 3125);
DISPLAY INVISIBLE (-5000 3125);
FORCEPROP 1 LAST COMMENT_BODY TRUE
J 2
(-4625 3150);
DISPLAY 0.872340 (-4625 3150);
PAINT GREEN (-4625 3150);
DISPLAY INVISIBLE (-4625 3150);
FORCEADD RES..2
(-2200 3650);
FORCEPROP 1 LASTPIN (-2200 3550) $PN 2
J 0
(-2195 3560);
DISPLAY 0.617021 (-2195 3560);
PAINT ORANGE (-2195 3560);
FORCEPROP 1 LASTPIN (-2200 3750) $PN 1
J 0
(-2195 3712);
DISPLAY 0.617021 (-2195 3712);
PAINT ORANGE (-2195 3712);
FORCEPROP 1 LAST WATTAGE 1/16W
J 0
(-2160 3625);
DISPLAY 0.617021 (-2160 3625);
PAINT SKYBLUE (-2160 3625);
FORCEPROP 1 LAST MATERIAL CHIP
J 0
(-2160 3575);
DISPLAY 0.617021 (-2160 3575);
PAINT SKYBLUE (-2160 3575);
FORCEPROP 1 LAST PACK_TYPE 0402
J 0
(-2160 3475);
DISPLAY 0.617021 (-2160 3475);
PAINT SKYBLUE (-2160 3475);
FORCEPROP 1 LAST TOLERANCE 1.0%
J 0
(-2155 3675);
DISPLAY 0.617021 (-2155 3675);
PAINT SKYBLUE (-2155 3675);
FORCEPROP 1 LAST VALUE 240
J 0
(-2155 3725);
DISPLAY 0.617021 (-2155 3725);
PAINT SKYBLUE (-2155 3725);
FORCEPROP 1 LAST PART_NUMBER G21796-294
J 0
(-2160 3525);
DISPLAY 0.617021 (-2160 3525);
PAINT BLUE (-2160 3525);
FORCEPROP 1 LAST LOCATION R9M18
J 0
(-2155 3775);
DISPLAY 0.617021 (-2155 3775);
PAINT AQUA (-2155 3775);
FORCEPROP 0 LAST ROOM SMB_PE_HP_CPU1
J 0
(-2150 3875);
DISPLAY 1.021277 (-2150 3875);
PAINT ORANGE (-2150 3875);
DISPLAY INVISIBLE (-2150 3875);
FORCEPROP 1 LAST PATH I6
J 0
(-2150 3825);
DISPLAY 0.978723 (-2150 3825);
PAINT WHITE (-2150 3825);
DISPLAY INVISIBLE (-2150 3825);
FORCEPROP 2 LAST SEC_TYPE 0402
J 0
(-2150 3875);
DISPLAY 1.021277 (-2150 3875);
PAINT ORANGE (-2150 3875);
DISPLAY INVISIBLE (-2150 3875);
FORCEPROP 2 LAST CDS_LIB mstr_discrete
J 0
(-2200 3650);
PAINT MONO (-2200 3650);
DISPLAY INVISIBLE (-2200 3650);
FORCEPROP 2 LAST SEC 1
J 0
(-2150 3875);
DISPLAY 0.680851 (-2150 3875);
PAINT MONO (-2150 3875);
DISPLAY INVISIBLE (-2150 3875);
FORCEPROP 2 LAST CDS_LOCATION R9M18
J 0
(-2155 3775);
DISPLAY 0.617021 (-2155 3775);
PAINT AQUA (-2155 3775);
DISPLAY INVISIBLE (-2155 3775);
FORCEADD RES..2
R 2
(-2325 3650);
FORCEPROP 1 LAST PACK_TYPE 0402
J 2
(-2365 3475);
DISPLAY 0.617021 (-2365 3475);
PAINT SKYBLUE (-2365 3475);
FORCEPROP 1 LASTPIN (-2325 3550) $PN 2
J 2
(-2330 3560);
DISPLAY 0.617021 (-2330 3560);
PAINT ORANGE (-2330 3560);
FORCEPROP 1 LASTPIN (-2325 3750) $PN 1
J 2
(-2330 3712);
DISPLAY 0.617021 (-2330 3712);
PAINT ORANGE (-2330 3712);
FORCEPROP 1 LAST WATTAGE 1/16W
J 2
(-2365 3625);
DISPLAY 0.617021 (-2365 3625);
PAINT SKYBLUE (-2365 3625);
FORCEPROP 1 LAST MATERIAL CHIP
J 2
(-2365 3575);
DISPLAY 0.617021 (-2365 3575);
PAINT SKYBLUE (-2365 3575);
FORCEPROP 1 LAST TOLERANCE 1.0%
J 2
(-2370 3675);
DISPLAY 0.617021 (-2370 3675);
PAINT SKYBLUE (-2370 3675);
FORCEPROP 1 LAST VALUE 240
J 2
(-2370 3725);
DISPLAY 0.617021 (-2370 3725);
PAINT SKYBLUE (-2370 3725);
FORCEPROP 1 LAST LOCATION R9M19
J 2
(-2370 3775);
DISPLAY 0.617021 (-2370 3775);
PAINT AQUA (-2370 3775);
FORCEPROP 1 LAST PART_NUMBER G21796-294
J 2
(-2365 3525);
DISPLAY 0.617021 (-2365 3525);
PAINT BLUE (-2365 3525);
FORCEPROP 0 LAST ROOM SMB_PE_HP_CPU1
J 0
(-2350 3875);
DISPLAY 1.021277 (-2350 3875);
PAINT ORANGE (-2350 3875);
DISPLAY INVISIBLE (-2350 3875);
FORCEPROP 1 LAST PATH I7
J 2
(-2375 3825);
DISPLAY 0.978723 (-2375 3825);
PAINT WHITE (-2375 3825);
DISPLAY INVISIBLE (-2375 3825);
FORCEPROP 2 LAST SEC_TYPE 0402
J 0
(-2375 3875);
DISPLAY 1.021277 (-2375 3875);
PAINT ORANGE (-2375 3875);
DISPLAY INVISIBLE (-2375 3875);
FORCEPROP 2 LAST CDS_LIB mstr_discrete
J 2
(-2325 3650);
PAINT MONO (-2325 3650);
DISPLAY INVISIBLE (-2325 3650);
FORCEPROP 2 LAST SEC 1
J 0
(-2375 3875);
DISPLAY 0.680851 (-2375 3875);
PAINT MONO (-2375 3875);
DISPLAY INVISIBLE (-2375 3875);
FORCEPROP 2 LAST CDS_LOCATION R9M19
J 2
(-2370 3775);
DISPLAY 0.617021 (-2370 3775);
PAINT AQUA (-2370 3775);
DISPLAY INVISIBLE (-2370 3775);
FORCEADD PVCCIO_CPU1..1
(-2250 4000);
FORCEPROP 3 LASTPIN (-2250 3950) SIG_NAME PVCCIO_CPU1\g
J 0
(-2240 3960);
DISPLAY 0.659574 (-2240 3960);
PAINT MONO (-2240 3960);
DISPLAY INVISIBLE (-2240 3960);
FORCEPROP 1 LAST PATH I8
J 0
(-2200 4025);
DISPLAY 0.872340 (-2200 4025);
PAINT AQUA (-2200 4025);
DISPLAY INVISIBLE (-2200 4025);
FORCEPROP 2 LAST CDS_LIB mstr_symbols
J 0
(-2250 4000);
PAINT ORANGE (-2250 4000);
DISPLAY INVISIBLE (-2250 4000);
FORCEPROP 1 LAST VOLTAGE 1.1V
J 0
(-2295 3957);
DISPLAY 0.340426 (-2295 3957);
PAINT SKYBLUE (-2295 3957);
DISPLAY INVISIBLE (-2295 3957);
FORCEPROP 1 LAST BODY_TYPE PLUMBING
J 0
(-2295 3957);
DISPLAY 0.340426 (-2295 3957);
PAINT GREEN (-2295 3957);
DISPLAY INVISIBLE (-2295 3957);
FORCEPROP 1 LAST HDL_POWER PVCCIO_CPU1
J 1
(-2250 4050);
DISPLAY 0.872340 (-2250 4050);
PAINT GREEN (-2250 4050);
DISPLAY INVISIBLE (-2250 4050);
FORCEADD PVCCIO_CPU1..1
(-1850 4150);
FORCEPROP 3 LASTPIN (-1850 4100) SIG_NAME PVCCIO_CPU1\g
J 0
(-1840 4110);
DISPLAY 0.659574 (-1840 4110);
PAINT MONO (-1840 4110);
DISPLAY INVISIBLE (-1840 4110);
FORCEPROP 1 LAST PATH I9
J 0
(-1800 4175);
DISPLAY 0.872340 (-1800 4175);
PAINT AQUA (-1800 4175);
DISPLAY INVISIBLE (-1800 4175);
FORCEPROP 2 LAST CDS_LIB mstr_symbols
J 0
(-1850 4150);
PAINT ORANGE (-1850 4150);
DISPLAY INVISIBLE (-1850 4150);
FORCEPROP 1 LAST VOLTAGE 1.1V
J 0
(-1895 4107);
DISPLAY 0.340426 (-1895 4107);
PAINT SKYBLUE (-1895 4107);
DISPLAY INVISIBLE (-1895 4107);
FORCEPROP 1 LAST BODY_TYPE PLUMBING
J 0
(-1895 4107);
DISPLAY 0.340426 (-1895 4107);
PAINT GREEN (-1895 4107);
DISPLAY INVISIBLE (-1895 4107);
FORCEPROP 1 LAST HDL_POWER PVCCIO_CPU1
J 1
(-1850 4200);
DISPLAY 0.872340 (-1850 4200);
PAINT GREEN (-1850 4200);
DISPLAY INVISIBLE (-1850 4200);
FORCEADD CAD_NOTE..1
(-3825 3075);
FORCEPROP 2 LAST CDS_LIB mstr_symbols
J 0
(-3825 3075);
PAINT MONO (-3825 3075);
DISPLAY INVISIBLE (-3825 3075);
FORCEPROP 1 LAST COMMENT_BODY TRUE
J 0
(-3800 3175);
DISPLAY 1.319149 (-3800 3175);
PAINT WHITE (-3800 3175);
DISPLAY INVISIBLE (-3800 3175);
FORCEADD DESIGN_NOTE..1
(-1575 2675);
FORCEPROP 2 LAST CDS_LIB mstr_symbols
J 0
(-1575 2675);
PAINT ORANGE (-1575 2675);
DISPLAY INVISIBLE (-1575 2675);
FORCEPROP 1 LAST COMMENT_BODY TRUE
J 0
(-1550 2775);
DISPLAY 0.978723 (-1550 2775);
PAINT ORANGE (-1550 2775);
DISPLAY INVISIBLE (-1550 2775);
FORCEADD CAD_NOTE..1
(-1575 4550);
FORCEPROP 2 LAST CDS_LIB mstr_symbols
J 0
(-1575 4550);
PAINT MONO (-1575 4550);
DISPLAY INVISIBLE (-1575 4550);
FORCEPROP 1 LAST COMMENT_BODY TRUE
J 0
(-1550 4650);
DISPLAY 1.319149 (-1550 4650);
PAINT WHITE (-1550 4650);
DISPLAY INVISIBLE (-1550 4650);
FORCEADD INTEL_CORP_BPAGE..1
(2650 500);
FORCEPROP 1 LAST CDS_CON_LAST_MODIFIED Fri Jun 16 17:49:01 2017
J 0
(1225 825);
PAINT ORANGE (1225 825);
DISPLAY INVISIBLE (1225 825);
FORCEPROP 1 LAST CUSTOM_TXT_CDS <CURRENT_DESIGN_SHEET> OF <TOTAL_DESIGN_SHEETS>
J 0
(2150 525);
PAINT ORANGE (2150 525);
FORCEPROP 1 LAST CUSTOM_TXT_CDS <CON_LAST_MODIFIED>
J 0
(-1350 600);
PAINT ORANGE (-1350 600);
FORCEPROP 2 LAST CUSTOM_TXT_CDS <XR_PAGE_TITLE>
J 0
(-5240 5750);
DISPLAY 0.638298 (-5240 5750);
PAINT PINK (-5240 5750);
DISPLAY INVISIBLE (-5240 5750);
FORCEPROP 1 LAST SCH_TITLE SMBUS: CPU PCIE HP
J 0
(-5300 550);
DISPLAY 1.212766 (-5300 550);
PAINT ORANGE (-5300 550);
FORCEPROP 2 LAST PAGE_BORDER TRUE
J 0
(-5240 5750);
DISPLAY 0.617021 (-5240 5750);
PAINT PINK (-5240 5750);
DISPLAY INVISIBLE (-5240 5750);
FORCEPROP 2 LAST CDS_LIB mstr_symbols
J 0
(2650 500);
PAINT MONO (2650 500);
DISPLAY INVISIBLE (2650 500);
FORCEPROP 1 LAST COMMENT_BODY TRUE
J 0
(2662 512);
DISPLAY 0.468085 (2662 512);
PAINT GREEN (2662 512);
DISPLAY INVISIBLE (2662 512);
FORCEPROP 2 LAST CDS_XR_PAGE_TITLE CR-163 : @BASEBOARD_FAB2_LIB.BASEBOARD_FAB2(SCH_1):PAGE163
J 0
(-5240 5750);
DISPLAY 0.638298 (-5240 5750);
PAINT PINK (-5240 5750);
DISPLAY INVISIBLE (-5240 5750);
WIRE 16 -1 (-1800 3750)(-1800 3650);
WIRE 16 -1 (-1150 3650)(-1150 3750);
WIRE 16 -1 (-1100 4100)(-1100 4000);
WIRE 16 -1 (-1100 4000)(-1050 4000);
WIRE 16 -1 (-1100 4000)(-1150 4000);
WIRE 16 -1 (-1150 4000)(-1150 3950);
WIRE 16 -1 (-1050 3350)(-1050 4000);
WIRE 16 -1 (-1150 3350)(-1050 3350);
WIRE 16 -1 (-525 3900)(-525 4000);
WIRE 16 -1 (-450 3900)(-525 3900);
WIRE 16 -1 (-525 3900)(-600 3900);
WIRE 16 -1 (-600 3900)(-600 3750);
WIRE 16 -1 (-450 3750)(-450 3900);
WIRE 16 -1 (-1900 3200)(-1900 3150);
WIRE 16 -1 (-1800 3200)(-1900 3200);
WIRE 16 -1 (-2250 3875)(-2250 3950);
WIRE 16 -1 (-2200 3875)(-2250 3875);
WIRE 16 -1 (-2250 3875)(-2325 3875);
WIRE 16 -1 (-2325 3750)(-2325 3875);
WIRE 16 -1 (-2200 3750)(-2200 3875);
WIRE 16 -1 (-1850 4100)(-1850 4000);
WIRE 16 -1 (-1900 4000)(-1850 4000);
WIRE 16 -1 (-1850 4000)(-1800 4000);
WIRE 16 -1 (-1800 4000)(-1800 3950);
WIRE 16 -1 (-1900 3350)(-1900 4000);
WIRE 16 -1 (-1800 3350)(-1900 3350);
WIRE 16 -1 (-2200 3250)(-3175 3250);
FORCEPROP 2 LAST SIG_NAME SMB_CPU1_PE_HP_GTL_R_SDA
J 0
(-2925 3260);
DISPLAY 0.617021 (-2925 3260);
PAINT ORANGE (-2925 3260);
FORCEPROP 2 LASTPROP $XRERR UNIQUE?
J 0
(-3165 3260);
DISPLAY 0.638298 (-3165 3260);
PAINT MONO (-3165 3260);
DISPLAY INVISIBLE (-3165 3260);
WIRE 16 -1 (-2200 3550)(-2200 3250);
WIRE 16 -1 (-1800 3250)(-2200 3250);
WIRE 16 682 (-4000 3525)(-4000 2825);
WIRE 16 682 (-2975 3525)(-4000 3525);
WIRE 16 682 (-4000 2825)(-2975 2825);
WIRE 16 682 (-2975 2825)(-2975 3525);
WIRE 16 -1 (-3700 3300)(-2325 3300);
FORCEPROP 2 LAST SIG_NAME SMB_CPU1_PE_HP_GTL_R_SCL
J 0
(-2975 3310);
DISPLAY 0.617021 (-2975 3310);
PAINT ORANGE (-2975 3310);
FORCEPROP 2 LASTPROP $XRERR UNIQUE?
J 0
(-3215 3310);
DISPLAY 0.638298 (-3215 3310);
PAINT MONO (-3215 3310);
DISPLAY INVISIBLE (-3215 3310);
WIRE 16 -1 (-2325 3300)(-1800 3300);
WIRE 16 -1 (-2325 3550)(-2325 3300);
WIRE 16 -1 (-1150 3300)(-600 3300);
FORCEPROP 0 LAST SIG_NAME SMB_PEHPCPU1_STBY_LVC3_R_SCL
J 0
(-1010 3310);
DISPLAY 0.617021 (-1010 3310);
PAINT ORANGE (-1010 3310);
FORCEPROP 2 LASTPROP $XRERR UNIQUE?
J 0
(-1250 3310);
DISPLAY 0.638298 (-1250 3310);
PAINT MONO (-1250 3310);
DISPLAY INVISIBLE (-1250 3310);
WIRE 16 -1 (-600 3300)(-150 3300);
WIRE 16 -1 (-600 3550)(-600 3300);
WIRE 16 -1 (-3900 3300)(-4625 3300);
FORCEPROP 2 LAST SIG_NAME SMB_CPU1_PE_HP_GTL_SCL
J 0
(-4600 3310);
DISPLAY 0.617021 (-4600 3310);
PAINT ORANGE (-4600 3310);
WIRE 16 -1 (-4625 3250)(-3375 3250);
FORCEPROP 2 LAST SIG_NAME SMB_CPU1_PE_HP_GTL_SDA
J 0
(-4600 3260);
DISPLAY 0.617021 (-4600 3260);
PAINT ORANGE (-4600 3260);
WIRE 16 -1 (50 3300)(1050 3300);
FORCEPROP 0 LAST SIG_NAME SMB_PEHPCPU1_STBY_LVC3_SCL
J 0
(365 3310);
DISPLAY 0.617021 (365 3310);
PAINT ORANGE (365 3310);
WIRE 16 -1 (1050 3250)(300 3250);
FORCEPROP 0 LAST SIG_NAME SMB_PEHPCPU1_STBY_LVC3_SDA
J 0
(365 3260);
DISPLAY 0.617021 (365 3260);
PAINT ORANGE (365 3260);
WIRE 3 2175 (-1750 3000)(-1200 3000);
WIRE 3 2175 (-1200 3550)(-1200 3000);
WIRE 3 2175 (-1750 3550)(-1750 3000);
WIRE 3 2175 (-1750 3550)(-1200 3550);
WIRE 16 -1 (-400 3200)(-1150 3200);
FORCEPROP 2 LAST SIG_NAME TP_SMB_PEHPCPU1_EN
J 0
(-1000 3210);
DISPLAY 0.617021 (-1000 3210);
PAINT ORANGE (-1000 3210);
FORCEPROP 2 LASTPROP $XRERR UNIQUE?
J 0
(-370 3200);
DISPLAY 0.638298 (-370 3200);
PAINT MONO (-370 3200);
DISPLAY INVISIBLE (-370 3200);
WIRE 16 -1 (-1150 3250)(-450 3250);
FORCEPROP 0 LAST SIG_NAME SMB_PEHPCPU1_STBY_LVC3_R_SDA
J 0
(-1010 3260);
DISPLAY 0.617021 (-1010 3260);
PAINT ORANGE (-1010 3260);
FORCEPROP 2 LASTPROP $XRERR UNIQUE?
J 0
(-1250 3260);
DISPLAY 0.638298 (-1250 3260);
PAINT MONO (-1250 3260);
DISPLAY INVISIBLE (-1250 3260);
WIRE 16 -1 (-450 3250)(100 3250);
WIRE 16 -1 (-450 3550)(-450 3250);
DOT 1 (-525 3900);
DOT 1 (-450 3250);
DOT 1 (-600 3300);
DOT 1 (-1100 4000);
DOT 1 (-1850 4000);
DOT 1 (-2250 3875);
DOT 1 (-2200 3250);
DOT 1 (-2325 3300);
FORCENOTE
PLACE CAPS & PU RESISTORS NEAR TCA9517
(-1725 4400) 0;
DISPLAY LEFT (-1725 4400);
DISPLAY 1.021277 (-1725 4400);
PAINT PURPLE (-1725 4400);
FORCENOTE
TP FAB1 CHANGE TO TCA9517 0106
(-1750 2925) 0;
DISPLAY LEFT (-1750 2925);
DISPLAY 1.021277 (-1750 2925);
PAINT RED (-1750 2925);
FORCENOTE
PE HP SMBUS ADDRESS 0X22
(-1775 2550) 0;
DISPLAY LEFT (-1775 2550);
DISPLAY 1.021277 (-1775 2550);
PAINT PURPLE (-1775 2550);
FORCENOTE
PLACE SEIRES RESISTORS NO MORE
(-3975 2950) 0;
DISPLAY LEFT (-3975 2950);
DISPLAY 0.808511 (-3975 2950);
PAINT PURPLE (-3975 2950);
FORCENOTE
THAN 3"  FROM CPU1
(-3975 2875) 0;
DISPLAY LEFT (-3975 2875);
DISPLAY 0.808511 (-3975 2875);
PAINT PURPLE (-3975 2875);
FORCENOTE
ROOM=SMB_PE_HP_CPU1
(-5250 700) 0;
DISPLAY LEFT (-5250 700);
DISPLAY 1.021277 (-5250 700);
PAINT PURPLE (-5250 700);
QUIT
